(kicad_pcb
	(version 20260206)
	(generator "pcbnew")
	(generator_version "10.0")
	(general
		(thickness 1.6)
		(legacy_teardrops no)
	)
	(paper "A4")
	(title_block
		(title "fcb — 12433-1M.1206WZS1330.brd")
		(comment 1 "Open Vault / Knox (Wiwynn) / footprints 201-208 of 495")
	)
	(layers
		(0 "F.Cu" signal "TOP")
		(4 "In1.Cu" signal "L2GND")
		(6 "In2.Cu" signal "L3VCC")
		(2 "B.Cu" signal "BOTTOM")
		(9 "F.Adhes" user "F.Adhesive")
		(11 "B.Adhes" user "B.Adhesive")
		(13 "F.Paste" user "Package Geometry/Pastemask Top")
		(15 "B.Paste" user "Package Geometry/Pastemask Bottom")
		(5 "F.SilkS" user "Ref Des/Silkscreen Top")
		(7 "B.SilkS" user "Ref Des/Silkscreen Bottom")
		(1 "F.Mask" user "Board Geometry/Soldermask Top")
		(3 "B.Mask" user "Board Geometry/Soldermask Bottom")
		(17 "Dwgs.User" user "User.Drawings")
		(19 "Cmts.User" user "User.Comments")
		(21 "Eco1.User" user "User.Eco1")
		(23 "Eco2.User" user "User.Eco2")
		(25 "Edge.Cuts" user "Board Geometry/Outline")
		(27 "Margin" user)
		(31 "F.CrtYd" user "Package Geometry/Place Bound Top")
		(29 "B.CrtYd" user "Package Geometry/Place Bound Bottom")
		(35 "F.Fab" user "Ref Des/Assembly Top")
		(33 "B.Fab" user "Ref Des/Assembly Bottom")
	)
	(footprint ""
		(layer "F.Cu")
		(at 8.4836 -62.7126 -90)
		(property "Reference" "R122"
			(at 0 0 270)
			(layer "F.SilkS")
			(hide yes)
			(effects
				(font
					(size 1.27 1.27)
				)
			)
		)
		(property "Value" "1K8R6J-GP"
			(at -0.0508 -4.8514 270)
			(unlocked yes)
			(layer "F.Fab")
			(hide yes)
			(effects
				(font
					(size 1.016 1.016)
					(thickness 0.1524)
				)
			)
		)
		(property "Device Type" "R1206H28"
			(at 0 -6.3754 270)
			(unlocked yes)
			(layer "F.Fab")
			(hide yes)
			(effects
				(font
					(size 1.016 1.016)
					(thickness 0.1524)
				)
			)
		)
		(duplicate_pad_numbers_are_jumpers no)
		(fp_line
			(start -1.016 2.2352)
			(end -1.016 -2.2352)
			(stroke
				(width 0.1524)
				(type default)
			)
			(layer "F.SilkS")
		)
		(fp_line
			(start 1.016 2.2352)
			(end -1.016 2.2352)
			(stroke
				(width 0.1524)
				(type default)
			)
			(layer "F.SilkS")
		)
		(fp_line
			(start -1.016 -2.2352)
			(end 1.016 -2.2352)
			(stroke
				(width 0.1524)
				(type default)
			)
			(layer "F.SilkS")
		)
		(fp_line
			(start 1.016 -2.2352)
			(end 1.016 2.2352)
			(stroke
				(width 0.1524)
				(type default)
			)
			(layer "F.SilkS")
		)
		(fp_rect
			(start -1.0922 2.3114)
			(end 1.0922 -2.3114)
			(stroke
				(width 0)
				(type default)
			)
			(fill no)
			(layer "F.CrtYd")
		)
		(fp_poly
			(pts
				(xy -1.0922 -2.3114) (xy 1.0922 -2.3114) (xy 1.0922 2.3114) (xy -1.0922 2.3114)
			)
			(stroke
				(width 0)
				(type default)
			)
			(fill no)
			(layer "F.Fab")
		)
		(pad "1" smd rect
			(at 0 -1.397 270)
			(size 1.651 1.27)
			(layers "F.Cu" "F.Mask" "F.Paste")
			(net "P12V")
		)
		(pad "2" smd rect
			(at 0 1.397 270)
			(size 1.651 1.27)
			(layers "F.Cu" "F.Mask" "F.Paste")
			(net "LED_DR_LED5_BLUE")
		)
	)
	(footprint ""
		(layer "F.Cu")
		(at 23.63851 -151.325834)
		(property "Reference" "R12"
			(at 0 0 0)
			(layer "F.SilkS")
			(hide yes)
			(effects
				(font
					(size 1.27 1.27)
				)
			)
		)
		(property "Value" "4K7R2F-GP"
			(at 0.064008 -3.993896 0)
			(unlocked yes)
			(layer "F.Fab")
			(hide yes)
			(effects
				(font
					(size 1.016 1.016)
					(thickness 0.1524)
				)
			)
		)
		(property "Device Type" "R402H16"
			(at 0.064008 -5.517896 0)
			(unlocked yes)
			(layer "F.Fab")
			(hide yes)
			(effects
				(font
					(size 1.016 1.016)
					(thickness 0.1524)
				)
			)
		)
		(duplicate_pad_numbers_are_jumpers no)
		(fp_line
			(start -0.508 -0.9398)
			(end -0.508 0.9398)
			(stroke
				(width 0.1524)
				(type default)
			)
			(layer "F.SilkS")
		)
		(fp_line
			(start 0.508 -0.9398)
			(end -0.508 -0.9398)
			(stroke
				(width 0.1524)
				(type default)
			)
			(layer "F.SilkS")
		)
		(fp_rect
			(start -0.508 0.9398)
			(end 0.508 -0.9398)
			(stroke
				(width 0)
				(type default)
			)
			(fill no)
			(layer "F.CrtYd")
		)
		(fp_rect
			(start -0.508 0.9398)
			(end 0.508 -0.9398)
			(stroke
				(width 0)
				(type default)
			)
			(fill no)
			(layer "F.Fab")
		)
		(pad "1" smd custom
			(at 0 -0.4445)
			(size 0.1397 0.1397)
			(layers "F.Cu" "F.Mask" "F.Paste")
			(net "NCT7904_RESET")
			(options
				(clearance outline)
				(anchor circle)
			)
			(primitives
				(gr_poly
					(pts
						(arc
							(start -0.1778 -0.2794)
							(mid -0.249642 -0.249642)
							(end -0.2794 -0.1778)
						)
						(arc
							(start -0.2794 0.1778)
							(mid -0.249642 0.249642)
							(end -0.1778 0.2794)
						)
						(arc
							(start 0.1778 0.2794)
							(mid 0.249642 0.249642)
							(end 0.2794 0.1778)
						)
						(arc
							(start 0.2794 -0.1778)
							(mid 0.249642 -0.249642)
							(end 0.1778 -0.2794)
						)
					)
					(width 0)
					(fill yes)
				)
			)
		)
		(pad "2" smd custom
			(at 0 0.4445)
			(size 0.1397 0.1397)
			(layers "F.Cu" "F.Mask" "F.Paste")
			(net "P3V3")
			(options
				(clearance outline)
				(anchor circle)
			)
			(primitives
				(gr_poly
					(pts
						(arc
							(start -0.1778 -0.2794)
							(mid -0.249642 -0.249642)
							(end -0.2794 -0.1778)
						)
						(arc
							(start -0.2794 0.1778)
							(mid -0.249642 0.249642)
							(end -0.1778 0.2794)
						)
						(arc
							(start 0.1778 0.2794)
							(mid 0.249642 0.249642)
							(end 0.2794 0.1778)
						)
						(arc
							(start 0.2794 -0.1778)
							(mid 0.249642 -0.249642)
							(end 0.1778 -0.2794)
						)
					)
					(width 0)
					(fill yes)
				)
			)
		)
	)
	(footprint ""
		(layer "F.Cu")
		(at 27.7876 -150.7998 90)
		(property "Reference" "C7"
			(at 0 0 90)
			(layer "F.SilkS")
			(hide yes)
			(effects
				(font
					(size 1.27 1.27)
				)
			)
		)
		(property "Value" "SC2200P50V2KX-2GP"
			(at 1.1811 -2.7051 90)
			(unlocked yes)
			(layer "F.Fab")
			(hide yes)
			(effects
				(font
					(size 1.016 1.016)
					(thickness 0.1524)
				)
			)
		)
		(property "Device Type" "C402H22"
			(at 1.1811 -4.2291 90)
			(unlocked yes)
			(layer "F.Fab")
			(hide yes)
			(effects
				(font
					(size 1.016 1.016)
					(thickness 0.1524)
				)
			)
		)
		(duplicate_pad_numbers_are_jumpers no)
		(fp_rect
			(start -0.4318 0.9525)
			(end 0.4318 -0.9525)
			(stroke
				(width 0)
				(type default)
			)
			(fill no)
			(layer "F.CrtYd")
		)
		(fp_rect
			(start -0.4318 0.9525)
			(end 0.4318 -0.9525)
			(stroke
				(width 0)
				(type default)
			)
			(fill no)
			(layer "F.Fab")
		)
		(pad "1" smd custom
			(at 0 -0.4445 90)
			(size 0.1524 0.1524)
			(layers "F.Cu" "F.Mask" "F.Paste")
			(net "NCT7904_D1+")
			(options
				(clearance outline)
				(anchor circle)
			)
			(primitives
				(gr_poly
					(pts
						(arc
							(start 0.3048 -0.2032)
							(mid 0.275042 -0.275042)
							(end 0.2032 -0.3048)
						)
						(arc
							(start -0.2032 -0.3048)
							(mid -0.275042 -0.275042)
							(end -0.3048 -0.2032)
						)
						(arc
							(start -0.3048 0.2032)
							(mid -0.275042 0.275042)
							(end -0.2032 0.3048)
						)
						(arc
							(start 0.2032 0.3048)
							(mid 0.275042 0.275042)
							(end 0.3048 0.2032)
						)
					)
					(width 0)
					(fill yes)
				)
			)
		)
		(pad "2" smd custom
			(at 0 0.4445 90)
			(size 0.1524 0.1524)
			(layers "F.Cu" "F.Mask" "F.Paste")
			(net "NCT7904_D1-")
			(options
				(clearance outline)
				(anchor circle)
			)
			(primitives
				(gr_poly
					(pts
						(arc
							(start 0.3048 -0.2032)
							(mid 0.275042 -0.275042)
							(end 0.2032 -0.3048)
						)
						(arc
							(start -0.2032 -0.3048)
							(mid -0.275042 -0.275042)
							(end -0.3048 -0.2032)
						)
						(arc
							(start -0.3048 0.2032)
							(mid -0.275042 0.275042)
							(end -0.2032 0.3048)
						)
						(arc
							(start 0.2032 0.3048)
							(mid 0.275042 0.275042)
							(end 0.3048 0.2032)
						)
					)
					(width 0)
					(fill yes)
				)
			)
		)
	)
	(footprint ""
		(layer "F.Cu")
		(at 34.29 -254.381 180)
		(property "Reference" "R106"
			(at 0 0 180)
			(layer "F.SilkS")
			(hide yes)
			(effects
				(font
					(size 1.27 1.27)
				)
			)
		)
		(property "Value" "0R2J-2-GP"
			(at 0.064008 -3.993896 180)
			(unlocked yes)
			(layer "F.Fab")
			(hide yes)
			(effects
				(font
					(size 1.016 1.016)
					(thickness 0.1524)
				)
			)
		)
		(property "Device Type" "R402H16"
			(at 0.064008 -5.517896 180)
			(unlocked yes)
			(layer "F.Fab")
			(hide yes)
			(effects
				(font
					(size 1.016 1.016)
					(thickness 0.1524)
				)
			)
		)
		(duplicate_pad_numbers_are_jumpers no)
		(fp_line
			(start 0.508 -0.9398)
			(end -0.508 -0.9398)
			(stroke
				(width 0.1524)
				(type default)
			)
			(layer "F.SilkS")
		)
		(fp_line
			(start -0.508 -0.9398)
			(end -0.508 0.9398)
			(stroke
				(width 0.1524)
				(type default)
			)
			(layer "F.SilkS")
		)
		(fp_rect
			(start -0.508 0.9398)
			(end 0.508 -0.9398)
			(stroke
				(width 0)
				(type default)
			)
			(fill no)
			(layer "F.CrtYd")
		)
		(fp_rect
			(start -0.508 0.9398)
			(end 0.508 -0.9398)
			(stroke
				(width 0)
				(type default)
			)
			(fill no)
			(layer "F.Fab")
		)
		(pad "1" smd custom
			(at 0 -0.4445 180)
			(size 0.1397 0.1397)
			(layers "F.Cu" "F.Mask" "F.Paste")
			(net "I2C_C_SDA_LEDDRV")
			(options
				(clearance outline)
				(anchor circle)
			)
			(primitives
				(gr_poly
					(pts
						(arc
							(start -0.1778 -0.2794)
							(mid -0.249642 -0.249642)
							(end -0.2794 -0.1778)
						)
						(arc
							(start -0.2794 0.1778)
							(mid -0.249642 0.249642)
							(end -0.1778 0.2794)
						)
						(arc
							(start 0.1778 0.2794)
							(mid 0.249642 0.249642)
							(end 0.2794 0.1778)
						)
						(arc
							(start 0.2794 -0.1778)
							(mid 0.249642 -0.249642)
							(end 0.1778 -0.2794)
						)
					)
					(width 0)
					(fill yes)
				)
			)
		)
		(pad "2" smd custom
			(at 0 0.4445 180)
			(size 0.1397 0.1397)
			(layers "F.Cu" "F.Mask" "F.Paste")
			(net "I2C_C_SDA")
			(options
				(clearance outline)
				(anchor circle)
			)
			(primitives
				(gr_poly
					(pts
						(arc
							(start -0.1778 -0.2794)
							(mid -0.249642 -0.249642)
							(end -0.2794 -0.1778)
						)
						(arc
							(start -0.2794 0.1778)
							(mid -0.249642 0.249642)
							(end -0.1778 0.2794)
						)
						(arc
							(start 0.1778 0.2794)
							(mid 0.249642 0.249642)
							(end 0.2794 0.1778)
						)
						(arc
							(start 0.2794 -0.1778)
							(mid 0.249642 -0.249642)
							(end 0.1778 -0.2794)
						)
					)
					(width 0)
					(fill yes)
				)
			)
		)
	)
	(footprint ""
		(layer "F.Cu")
		(at 29.6672 -149.071584 180)
		(property "Reference" "R16"
			(at 0 0 180)
			(layer "F.SilkS")
			(hide yes)
			(effects
				(font
					(size 1.27 1.27)
				)
			)
		)
		(property "Value" "110KR2F-L-GP"
			(at 0.064008 -3.993896 180)
			(unlocked yes)
			(layer "F.Fab")
			(hide yes)
			(effects
				(font
					(size 1.016 1.016)
					(thickness 0.1524)
				)
			)
		)
		(property "Device Type" "R402H16"
			(at 0.064008 -5.517896 180)
			(unlocked yes)
			(layer "F.Fab")
			(hide yes)
			(effects
				(font
					(size 1.016 1.016)
					(thickness 0.1524)
				)
			)
		)
		(duplicate_pad_numbers_are_jumpers no)
		(fp_line
			(start 0.508 -0.9398)
			(end -0.508 -0.9398)
			(stroke
				(width 0.1524)
				(type default)
			)
			(layer "F.SilkS")
		)
		(fp_line
			(start -0.508 -0.9398)
			(end -0.508 0.9398)
			(stroke
				(width 0.1524)
				(type default)
			)
			(layer "F.SilkS")
		)
		(fp_rect
			(start -0.508 0.9398)
			(end 0.508 -0.9398)
			(stroke
				(width 0)
				(type default)
			)
			(fill no)
			(layer "F.CrtYd")
		)
		(fp_rect
			(start -0.508 0.9398)
			(end 0.508 -0.9398)
			(stroke
				(width 0)
				(type default)
			)
			(fill no)
			(layer "F.Fab")
		)
		(pad "1" smd custom
			(at 0 -0.4445 180)
			(size 0.1397 0.1397)
			(layers "F.Cu" "F.Mask" "F.Paste")
			(net "P12VL")
			(options
				(clearance outline)
				(anchor circle)
			)
			(primitives
				(gr_poly
					(pts
						(arc
							(start -0.1778 -0.2794)
							(mid -0.249642 -0.249642)
							(end -0.2794 -0.1778)
						)
						(arc
							(start -0.2794 0.1778)
							(mid -0.249642 0.249642)
							(end -0.1778 0.2794)
						)
						(arc
							(start 0.1778 0.2794)
							(mid 0.249642 0.249642)
							(end 0.2794 0.1778)
						)
						(arc
							(start 0.2794 -0.1778)
							(mid 0.249642 -0.249642)
							(end 0.1778 -0.2794)
						)
					)
					(width 0)
					(fill yes)
				)
			)
		)
		(pad "2" smd custom
			(at 0 0.4445 180)
			(size 0.1397 0.1397)
			(layers "F.Cu" "F.Mask" "F.Paste")
			(net "NCT7904_VSEN6")
			(options
				(clearance outline)
				(anchor circle)
			)
			(primitives
				(gr_poly
					(pts
						(arc
							(start -0.1778 -0.2794)
							(mid -0.249642 -0.249642)
							(end -0.2794 -0.1778)
						)
						(arc
							(start -0.2794 0.1778)
							(mid -0.249642 0.249642)
							(end -0.1778 0.2794)
						)
						(arc
							(start 0.1778 0.2794)
							(mid 0.249642 0.249642)
							(end 0.2794 0.1778)
						)
						(arc
							(start 0.2794 -0.1778)
							(mid 0.249642 -0.249642)
							(end 0.1778 -0.2794)
						)
					)
					(width 0)
					(fill yes)
				)
			)
		)
	)
	(footprint ""
		(layer "F.Cu")
		(at 7.3406 -174.7774 180)
		(property "Reference" "C52"
			(at 0 0 180)
			(layer "F.SilkS")
			(hide yes)
			(effects
				(font
					(size 1.27 1.27)
				)
			)
		)
		(property "Value" "SCD1U50V3KX-GP"
			(at 0 -2.8194 180)
			(unlocked yes)
			(layer "F.Fab")
			(hide yes)
			(effects
				(font
					(size 1.016 1.016)
					(thickness 0.1524)
				)
			)
		)
		(property "Device Type" "C603H36"
			(at 0 -4.3434 180)
			(unlocked yes)
			(layer "F.Fab")
			(hide yes)
			(effects
				(font
					(size 1.016 1.016)
					(thickness 0.1524)
				)
			)
		)
		(duplicate_pad_numbers_are_jumpers no)
		(fp_line
			(start 0.508 0)
			(end -0.508 0)
			(stroke
				(width 0.2032)
				(type default)
			)
			(layer "F.SilkS")
		)
		(fp_rect
			(start -0.5842 1.3335)
			(end 0.5842 -1.3335)
			(stroke
				(width 0)
				(type default)
			)
			(fill no)
			(layer "F.CrtYd")
		)
		(fp_rect
			(start -0.5842 1.3335)
			(end 0.5842 -1.3335)
			(stroke
				(width 0)
				(type default)
			)
			(fill no)
			(layer "F.Fab")
		)
		(pad "1" smd custom
			(at 0 -0.762 180)
			(size 0.2159 0.2159)
			(layers "F.Cu" "F.Mask" "F.Paste")
			(net "P3V3")
			(options
				(clearance outline)
				(anchor circle)
			)
			(primitives
				(gr_poly
					(pts
						(arc
							(start -0.3302 -0.4318)
							(mid -0.402042 -0.402042)
							(end -0.4318 -0.3302)
						)
						(arc
							(start -0.4318 0.3302)
							(mid -0.402042 0.402042)
							(end -0.3302 0.4318)
						)
						(arc
							(start 0.3302 0.4318)
							(mid 0.402042 0.402042)
							(end 0.4318 0.3302)
						)
						(arc
							(start 0.4318 -0.3302)
							(mid 0.402042 -0.402042)
							(end 0.3302 -0.4318)
						)
					)
					(width 0)
					(fill yes)
				)
			)
		)
		(pad "2" smd custom
			(at 0 0.762 180)
			(size 0.2159 0.2159)
			(layers "F.Cu" "F.Mask" "F.Paste")
			(net "GND")
			(options
				(clearance outline)
				(anchor circle)
			)
			(primitives
				(gr_poly
					(pts
						(arc
							(start -0.3302 -0.4318)
							(mid -0.402042 -0.402042)
							(end -0.4318 -0.3302)
						)
						(arc
							(start -0.4318 0.3302)
							(mid -0.402042 0.402042)
							(end -0.3302 0.4318)
						)
						(arc
							(start 0.3302 0.4318)
							(mid 0.402042 0.402042)
							(end 0.4318 0.3302)
						)
						(arc
							(start 0.4318 -0.3302)
							(mid 0.402042 -0.402042)
							(end 0.3302 -0.4318)
						)
					)
					(width 0)
					(fill yes)
				)
			)
		)
	)
	(footprint ""
		(layer "F.Cu")
		(at 26.289 -248.158 180)
		(property "Reference" "PC42"
			(at 0 0 180)
			(layer "F.SilkS")
			(hide yes)
			(effects
				(font
					(size 1.27 1.27)
				)
			)
		)
		(property "Value" "SC22P50V3JN-DLGP"
			(at 0 -2.8194 180)
			(unlocked yes)
			(layer "F.Fab")
			(hide yes)
			(effects
				(font
					(size 1.016 1.016)
					(thickness 0.1524)
				)
			)
		)
		(property "Device Type" "C603H36"
			(at 0 -4.3434 180)
			(unlocked yes)
			(layer "F.Fab")
			(hide yes)
			(effects
				(font
					(size 1.016 1.016)
					(thickness 0.1524)
				)
			)
		)
		(duplicate_pad_numbers_are_jumpers no)
		(fp_line
			(start 0.508 0)
			(end -0.508 0)
			(stroke
				(width 0.2032)
				(type default)
			)
			(layer "F.SilkS")
		)
		(fp_rect
			(start -0.5842 1.3335)
			(end 0.5842 -1.3335)
			(stroke
				(width 0)
				(type default)
			)
			(fill no)
			(layer "F.CrtYd")
		)
		(fp_rect
			(start -0.5842 1.3335)
			(end 0.5842 -1.3335)
			(stroke
				(width 0)
				(type default)
			)
			(fill no)
			(layer "F.Fab")
		)
		(pad "1" smd custom
			(at 0 -0.762 180)
			(size 0.2159 0.2159)
			(layers "F.Cu" "F.Mask" "F.Paste")
			(net "P3V3_LX_COPPER")
			(options
				(clearance outline)
				(anchor circle)
			)
			(primitives
				(gr_poly
					(pts
						(arc
							(start -0.3302 -0.4318)
							(mid -0.402042 -0.402042)
							(end -0.4318 -0.3302)
						)
						(arc
							(start -0.4318 0.3302)
							(mid -0.402042 0.402042)
							(end -0.3302 0.4318)
						)
						(arc
							(start 0.3302 0.4318)
							(mid 0.402042 0.402042)
							(end 0.4318 0.3302)
						)
						(arc
							(start 0.4318 -0.3302)
							(mid 0.402042 -0.402042)
							(end 0.3302 -0.4318)
						)
					)
					(width 0)
					(fill yes)
				)
			)
		)
		(pad "2" smd custom
			(at 0 0.762 180)
			(size 0.2159 0.2159)
			(layers "F.Cu" "F.Mask" "F.Paste")
			(net "P3V3_FB")
			(options
				(clearance outline)
				(anchor circle)
			)
			(primitives
				(gr_poly
					(pts
						(arc
							(start -0.3302 -0.4318)
							(mid -0.402042 -0.402042)
							(end -0.4318 -0.3302)
						)
						(arc
							(start -0.4318 0.3302)
							(mid -0.402042 0.402042)
							(end -0.3302 0.4318)
						)
						(arc
							(start 0.3302 0.4318)
							(mid 0.402042 0.402042)
							(end 0.4318 0.3302)
						)
						(arc
							(start 0.4318 -0.3302)
							(mid 0.402042 -0.402042)
							(end 0.3302 -0.4318)
						)
					)
					(width 0)
					(fill yes)
				)
			)
		)
	)
	(footprint ""
		(layer "F.Cu")
		(at 44.704 -122.428)
		(property "Reference" "PR62"
			(at 0 0 0)
			(layer "F.SilkS")
			(hide yes)
			(effects
				(font
					(size 1.27 1.27)
				)
			)
		)
		(property "Value" "D002R2512F-GP"
			(at -3.228594 -1.194054 0)
			(unlocked yes)
			(layer "F.Fab")
			(hide yes)
			(effects
				(font
					(size 1.016 1.016)
					(thickness 0.1524)
				)
			)
		)
		(property "Device Type" "R2512-2H32"
			(at -3.228594 -2.718054 0)
			(unlocked yes)
			(layer "F.Fab")
			(hide yes)
			(effects
				(font
					(size 1.016 1.016)
					(thickness 0.1524)
				)
			)
		)
		(duplicate_pad_numbers_are_jumpers no)
		(fp_line
			(start -1.9685 -3.81)
			(end 1.9685 -3.81)
			(stroke
				(width 0.1524)
				(type default)
			)
			(layer "F.SilkS")
		)
		(fp_line
			(start -1.9685 3.81)
			(end -1.9685 -3.81)
			(stroke
				(width 0.1524)
				(type default)
			)
			(layer "F.SilkS")
		)
		(fp_line
			(start 1.9685 -3.81)
			(end 1.9685 3.81)
			(stroke
				(width 0.1524)
				(type default)
			)
			(layer "F.SilkS")
		)
		(fp_line
			(start 1.9685 3.81)
			(end -1.9685 3.81)
			(stroke
				(width 0.1524)
				(type default)
			)
			(layer "F.SilkS")
		)
		(fp_rect
			(start -1.5875 3.175)
			(end 1.5875 -3.175)
			(stroke
				(width 0)
				(type default)
			)
			(fill no)
			(layer "F.CrtYd")
		)
		(fp_poly
			(pts
				(xy -2.2225 3.8862) (xy -2.2225 0.00254) (xy -1.5875 0.00254) (xy -1.5875 3.175) (xy 1.5875 3.175)
				(xy 1.5875 -3.175) (xy -1.5875 -3.175) (xy -1.5875 -0.00254) (xy -2.2225 -0.00254) (xy -2.2225 -3.8862)
				(xy 2.2225 -3.8862) (xy 2.2225 3.8862)
			)
			(stroke
				(width 0)
				(type default)
			)
			(fill no)
			(layer "F.CrtYd")
		)
		(fp_rect
			(start -2.2225 3.8862)
			(end 2.2225 -3.8862)
			(stroke
				(width 0)
				(type default)
			)
			(fill no)
			(layer "F.Fab")
		)
		(pad "1" smd rect
			(at 0 -2.273808)
			(size 3.429 2.5654)
			(layers "F.Cu" "F.Mask" "F.Paste")
			(net "P12V")
		)
		(pad "2" smd rect
			(at 0 2.273808)
			(size 3.429 2.5654)
			(layers "F.Cu" "F.Mask" "F.Paste")
			(net "P12VL_NET")
		)
	)
)
